# S9S_MB_2U (Grand Teton) — schematic netlist excerpt (pin names and nets, part order shuffled) for the footprints in the layout excerpt that follows; sources: Cadence DE-HDL packaged netlist, KiCad conversion of 03242023_DA0F0TMBIJ0_F0T_Motherboard_J_brd_V01_OCP.brd

PR1303  Q_RES  22.6K 1% CHIP  pkg 0402LF  page 282 : A = PVNN_MAIN_CPU0_CS ; B = GND

(kicad_pcb
	(version 20260206)
	(generator "pcbnew")
	(generator_version "10.0")
	(general
		(thickness 1.6)
		(legacy_teardrops no)
	)
	(paper "A4")
	(title_block
		(title "03242023_DA0F0TMBIJ0_F0T_Motherboard_J_brd_V01_OCP.brd")
		(comment 1 "Grand Teton / footprints 1681-1681 of 6105")
	)
	(layers
		(0 "F.Cu" signal "TOP")
		(4 "In1.Cu" signal "GND")
		(6 "In2.Cu" signal "IN1")
		(8 "In3.Cu" signal "GND1")
		(10 "In4.Cu" signal "IN2")
		(12 "In5.Cu" signal "GND2")
		(14 "In6.Cu" signal "IN3")
		(16 "In7.Cu" signal "GND3")
		(18 "In8.Cu" signal "VCC")
		(20 "In9.Cu" signal "VCC1")
		(22 "In10.Cu" signal "GND4")
		(24 "In11.Cu" signal "IN4")
		(26 "In12.Cu" signal "GND5")
		(28 "In13.Cu" signal "IN5")
		(30 "In14.Cu" signal "GND6")
		(32 "In15.Cu" signal "IN6")
		(34 "In16.Cu" signal "GND7")
		(2 "B.Cu" signal "BOTTOM")
		(9 "F.Adhes" user "F.Adhesive")
		(11 "B.Adhes" user "B.Adhesive")
		(13 "F.Paste" user "Package Geometry/Pastemask Top")
		(15 "B.Paste" user "Package Geometry/Pastemask Bottom")
		(5 "F.SilkS" user "Ref Des/Silkscreen Top")
		(7 "B.SilkS" user "Ref Des/Silkscreen Bottom")
		(1 "F.Mask" user "Board Geometry/Soldermask Top")
		(3 "B.Mask" user "Board Geometry/Soldermask Bottom")
		(17 "Dwgs.User" user "User.Drawings")
		(19 "Cmts.User" user "User.Comments")
		(21 "Eco1.User" user "User.Eco1")
		(23 "Eco2.User" user "User.Eco2")
		(25 "Edge.Cuts" user "Board Geometry/Outline")
		(27 "Margin" user)
		(31 "F.CrtYd" user "Package Geometry/Place Bound Top")
		(29 "B.CrtYd" user "Package Geometry/Place Bound Bottom")
		(35 "F.Fab" user "Ref Des/Assembly Top")
		(33 "B.Fab" user "Ref Des/Assembly Bottom")
	)
	(footprint ""
		(layer "F.Cu")
		(at 430.643284 -179.201572 -90)
		(property "Reference" "PR1303"
			(at 0 0 270)
			(layer "F.SilkS")
			(hide yes)
			(effects
				(font
					(size 1.27 1.27)
				)
			)
		)
		(property "Value" ""
			(at 0 0 270)
			(layer "F.Fab")
			(effects
				(font
					(size 1.27 1.27)
				)
			)
		)
		(duplicate_pad_numbers_are_jumpers no)
		(fp_line
			(start -0.7874 0.4064)
			(end -0.7874 -0.4064)
			(stroke
				(width 0.1524)
				(type default)
			)
			(layer "F.SilkS")
		)
		(fp_line
			(start 0.7874 0.4064)
			(end -0.7874 0.4064)
			(stroke
				(width 0.1524)
				(type default)
			)
			(layer "F.SilkS")
		)
		(fp_line
			(start -0.7874 -0.4064)
			(end 0.7874 -0.4064)
			(stroke
				(width 0.1524)
				(type default)
			)
			(layer "F.SilkS")
		)
		(fp_line
			(start 0.7874 -0.4064)
			(end 0.7874 0.4064)
			(stroke
				(width 0.1524)
				(type default)
			)
			(layer "F.SilkS")
		)
		(fp_line
			(start -0.67945 0.3048)
			(end -0.67945 -0.305054)
			(stroke
				(width 0.1)
				(type default)
			)
			(layer "F.Fab")
		)
		(fp_line
			(start -0.12065 0.3048)
			(end -0.67945 0.3048)
			(stroke
				(width 0.1)
				(type default)
			)
			(layer "F.Fab")
		)
		(fp_line
			(start 0.120396 0.3048)
			(end 0.120396 0.2794)
			(stroke
				(width 0.1)
				(type default)
			)
			(layer "F.Fab")
		)
		(fp_line
			(start 0.67945 0.3048)
			(end 0.120396 0.3048)
			(stroke
				(width 0.1)
				(type default)
			)
			(layer "F.Fab")
		)
		(fp_line
			(start -0.12065 0.2794)
			(end -0.12065 0.3048)
			(stroke
				(width 0.1)
				(type default)
			)
			(layer "F.Fab")
		)
		(fp_line
			(start 0.120396 0.2794)
			(end -0.12065 0.2794)
			(stroke
				(width 0.1)
				(type default)
			)
			(layer "F.Fab")
		)
		(fp_line
			(start -0.12065 -0.2794)
			(end 0.12065 -0.2794)
			(stroke
				(width 0.1)
				(type default)
			)
			(layer "F.Fab")
		)
		(fp_line
			(start 0.12065 -0.2794)
			(end 0.12065 -0.3048)
			(stroke
				(width 0.1)
				(type default)
			)
			(layer "F.Fab")
		)
		(fp_line
			(start 0.12065 -0.3048)
			(end 0.67945 -0.3048)
			(stroke
				(width 0.1)
				(type default)
			)
			(layer "F.Fab")
		)
		(fp_line
			(start 0.67945 -0.3048)
			(end 0.67945 0.3048)
			(stroke
				(width 0.1)
				(type default)
			)
			(layer "F.Fab")
		)
		(fp_line
			(start -0.67945 -0.305054)
			(end -0.12065 -0.305054)
			(stroke
				(width 0.1)
				(type default)
			)
			(layer "F.Fab")
		)
		(fp_line
			(start -0.12065 -0.305054)
			(end -0.12065 -0.2794)
			(stroke
				(width 0.1)
				(type default)
			)
			(layer "F.Fab")
		)
		(pad "1" smd circle
			(at -0.40005 0 270)
			(size 0 0)
			(layers "F.Cu" "F.Mask" "F.Paste")
			(net "PVNN_MAIN_CPU0_CS")
		)
		(pad "2" smd circle
			(at 0.40005 0 270)
			(size 0 0)
			(layers "F.Cu" "F.Mask" "F.Paste")
			(net "GND")
		)
	)
)
